# BASEBOARD_FAB2 (Tioga Pass) — schematic netlist excerpt (pin names and nets, part order shuffled) for the footprints in the layout excerpt that follows; sources: Cadence DE-HDL packaged netlist, KiCad conversion of Wiwynn_Tioga_Pass_MB.brd

C2M16  CAP_A  1.0UF 6.3V 10% X6S  pkg 0402V  page 130 : A = P3V3_STBY ; B = GND
R6P23  RES  4.75K 1% EMPTY  pkg 0402  page 102 : A = FM_100M_N ; B = GND
R3P32  RES  1.00K 1% CHIP  pkg 0402  page 96 : A = GND ; B = PD_GTL2014_1_VREF

(kicad_pcb
	(version 20260206)
	(generator "pcbnew")
	(generator_version "10.0")
	(general
		(thickness 1.6)
		(legacy_teardrops no)
	)
	(paper "A4")
	(title_block
		(title "Wiwynn_Tioga_Pass_MB.brd")
		(comment 1 "Tioga Pass / footprints 3950-3952 of 4770")
	)
	(layers
		(0 "F.Cu" signal "TOP")
		(4 "In1.Cu" signal "L2GND")
		(6 "In2.Cu" signal "L3")
		(8 "In3.Cu" signal "L4GND")
		(10 "In4.Cu" signal "L5")
		(12 "In5.Cu" signal "L6GND")
		(14 "In6.Cu" signal "L7VCC")
		(16 "In7.Cu" signal "L8VCC")
		(18 "In8.Cu" signal "L9GND")
		(20 "In9.Cu" signal "L10")
		(22 "In10.Cu" signal "L11GND")
		(24 "In11.Cu" signal "L12")
		(26 "In12.Cu" signal "L13GND")
		(2 "B.Cu" signal "BOTTOM")
		(9 "F.Adhes" user "F.Adhesive")
		(11 "B.Adhes" user "B.Adhesive")
		(13 "F.Paste" user "Package Geometry/Pastemask Top")
		(15 "B.Paste" user "Package Geometry/Pastemask Bottom")
		(5 "F.SilkS" user "Ref Des/Silkscreen Top")
		(7 "B.SilkS" user "Ref Des/Silkscreen Bottom")
		(1 "F.Mask" user "Board Geometry/Soldermask Top")
		(3 "B.Mask" user "Board Geometry/Soldermask Bottom")
		(17 "Dwgs.User" user "User.Drawings")
		(19 "Cmts.User" user "User.Comments")
		(21 "Eco1.User" user "User.Eco1")
		(23 "Eco2.User" user "User.Eco2")
		(25 "Edge.Cuts" user "Board Geometry/Outline")
		(27 "Margin" user)
		(31 "F.CrtYd" user "Package Geometry/Place Bound Top")
		(29 "B.CrtYd" user "Package Geometry/Place Bound Bottom")
		(35 "F.Fab" user "Ref Des/Assembly Top")
		(33 "B.Fab" user "Ref Des/Assembly Bottom")
	)
	(footprint ""
		(layer "B.Cu")
		(at 371.8306 -51.3207 180)
		(property "Reference" "R3P32"
			(at 0 0 0)
			(layer "B.SilkS")
			(hide yes)
			(effects
				(font
					(size 1.27 1.27)
				)
				(justify mirror)
			)
		)
		(property "Value" ""
			(at 0 0 0)
			(layer "B.Fab")
			(effects
				(font
					(size 1.27 1.27)
				)
				(justify mirror)
			)
		)
		(duplicate_pad_numbers_are_jumpers no)
		(fp_poly
			(pts
				(xy 0.2794 -0.1016) (xy -0.2794 -0.1016) (xy -0.2794 0.9906) (xy 0.2794 0.9906)
			)
			(stroke
				(width 0)
				(type default)
			)
			(fill no)
			(layer "B.CrtYd")
		)
		(fp_line
			(start 0.2794 0.9906)
			(end -0.2794 0.9906)
			(stroke
				(width 0.1)
				(type default)
			)
			(layer "B.Fab")
		)
		(fp_line
			(start 0.2794 -0.1016)
			(end 0.2794 0.9906)
			(stroke
				(width 0.1)
				(type default)
			)
			(layer "B.Fab")
		)
		(fp_line
			(start -0.2794 0.9906)
			(end -0.2794 -0.1016)
			(stroke
				(width 0.1)
				(type default)
			)
			(layer "B.Fab")
		)
		(fp_line
			(start -0.2794 -0.1016)
			(end 0.2794 -0.1016)
			(stroke
				(width 0.1)
				(type default)
			)
			(layer "B.Fab")
		)
		(pad "1" smd rect
			(at 0 0)
			(size 0.508 0.508)
			(layers "B.Cu" "B.Mask" "B.Paste")
			(net "GND")
		)
		(pad "2" smd rect
			(at 0 0.889)
			(size 0.508 0.508)
			(layers "B.Cu" "B.Mask" "B.Paste")
			(net "PD_GTL2014_1_VREF")
		)
		(zone
			(layer "B.Cu")
			(hatch none 0.5)
			(connect_pads
				(clearance 0)
			)
			(min_thickness 0.25)
			(keepout
				(tracks not_allowed)
				(vias allowed)
				(pads allowed)
				(copperpour not_allowed)
				(footprints allowed)
			)
			(placement
				(enabled no)
				(sheetname "")
			)
			(fill
				(thermal_gap 0.5)
				(thermal_bridge_width 0.5)
				(island_removal_mode 0)
			)
			(polygon
				(pts
					(xy 371.5766 -51.9557) (xy 372.0846 -51.9557) (xy 372.0846 -51.5747) (xy 371.5766 -51.5747)
				)
			)
		)
		(zone
			(layer "B.Cu")
			(hatch none 0.5)
			(connect_pads
				(clearance 0)
			)
			(min_thickness 0.25)
			(keepout
				(tracks allowed)
				(vias not_allowed)
				(pads allowed)
				(copperpour not_allowed)
				(footprints allowed)
			)
			(placement
				(enabled no)
				(sheetname "")
			)
			(fill
				(thermal_gap 0.5)
				(thermal_bridge_width 0.5)
				(island_removal_mode 0)
			)
			(polygon
				(pts
					(xy 371.5766 -51.5747) (xy 372.0846 -51.5747) (xy 372.0846 -51.9557) (xy 371.5766 -51.9557)
				)
			)
		)
	)
	(footprint ""
		(layer "B.Cu")
		(at 166.497 -74.549)
		(property "Reference" "R6P23"
			(at 0 0 0)
			(layer "B.SilkS")
			(hide yes)
			(effects
				(font
					(size 1.27 1.27)
				)
				(justify mirror)
			)
		)
		(property "Value" ""
			(at 0 0 0)
			(layer "B.Fab")
			(effects
				(font
					(size 1.27 1.27)
				)
				(justify mirror)
			)
		)
		(duplicate_pad_numbers_are_jumpers no)
		(fp_poly
			(pts
				(xy 0.2794 -0.1016) (xy -0.2794 -0.1016) (xy -0.2794 0.9906) (xy 0.2794 0.9906)
			)
			(stroke
				(width 0)
				(type default)
			)
			(fill no)
			(layer "B.CrtYd")
		)
		(fp_line
			(start -0.2794 -0.1016)
			(end 0.2794 -0.1016)
			(stroke
				(width 0.1)
				(type default)
			)
			(layer "B.Fab")
		)
		(fp_line
			(start -0.2794 0.9906)
			(end -0.2794 -0.1016)
			(stroke
				(width 0.1)
				(type default)
			)
			(layer "B.Fab")
		)
		(fp_line
			(start 0.2794 -0.1016)
			(end 0.2794 0.9906)
			(stroke
				(width 0.1)
				(type default)
			)
			(layer "B.Fab")
		)
		(fp_line
			(start 0.2794 0.9906)
			(end -0.2794 0.9906)
			(stroke
				(width 0.1)
				(type default)
			)
			(layer "B.Fab")
		)
		(pad "1" smd rect
			(at 0 0 180)
			(size 0.508 0.508)
			(layers "B.Cu" "B.Mask" "B.Paste")
			(net "FM_100M_N")
		)
		(pad "2" smd rect
			(at 0 0.889 180)
			(size 0.508 0.508)
			(layers "B.Cu" "B.Mask" "B.Paste")
			(net "GND")
		)
		(zone
			(layer "B.Cu")
			(hatch none 0.5)
			(connect_pads
				(clearance 0)
			)
			(min_thickness 0.25)
			(keepout
				(tracks allowed)
				(vias not_allowed)
				(pads allowed)
				(copperpour not_allowed)
				(footprints allowed)
			)
			(placement
				(enabled no)
				(sheetname "")
			)
			(fill
				(thermal_gap 0.5)
				(thermal_bridge_width 0.5)
				(island_removal_mode 0)
			)
			(polygon
				(pts
					(xy 166.751 -74.295) (xy 166.243 -74.295) (xy 166.243 -73.914) (xy 166.751 -73.914)
				)
			)
		)
		(zone
			(layer "B.Cu")
			(hatch none 0.5)
			(connect_pads
				(clearance 0)
			)
			(min_thickness 0.25)
			(keepout
				(tracks not_allowed)
				(vias allowed)
				(pads allowed)
				(copperpour not_allowed)
				(footprints allowed)
			)
			(placement
				(enabled no)
				(sheetname "")
			)
			(fill
				(thermal_gap 0.5)
				(thermal_bridge_width 0.5)
				(island_removal_mode 0)
			)
			(polygon
				(pts
					(xy 166.751 -73.914) (xy 166.243 -73.914) (xy 166.243 -74.295) (xy 166.751 -74.295)
				)
			)
		)
	)
	(footprint ""
		(layer "B.Cu")
		(at 392.041888 -115.315746 90)
		(property "Reference" "C2M16"
			(at 0 0 90)
			(layer "B.SilkS")
			(hide yes)
			(effects
				(font
					(size 1.27 1.27)
				)
				(justify mirror)
			)
		)
		(property "Value" ""
			(at 0 0 90)
			(layer "B.Fab")
			(effects
				(font
					(size 1.27 1.27)
				)
				(justify mirror)
			)
		)
		(duplicate_pad_numbers_are_jumpers no)
		(fp_poly
			(pts
				(xy -0.3048 -0.1016) (xy -0.3048 0.9906) (xy 0.3048 0.9906) (xy 0.3048 -0.1016)
			)
			(stroke
				(width 0)
				(type default)
			)
			(fill no)
			(layer "B.CrtYd")
		)
		(fp_line
			(start 0.3048 -0.1016)
			(end 0.3048 0.9906)
			(stroke
				(width 0.1)
				(type default)
			)
			(layer "B.Fab")
		)
		(fp_line
			(start -0.3048 -0.1016)
			(end 0.3048 -0.1016)
			(stroke
				(width 0.1)
				(type default)
			)
			(layer "B.Fab")
		)
		(fp_line
			(start 0.3048 0.9906)
			(end -0.3048 0.9906)
			(stroke
				(width 0.1)
				(type default)
			)
			(layer "B.Fab")
		)
		(fp_line
			(start -0.3048 0.9906)
			(end -0.3048 -0.1016)
			(stroke
				(width 0.1)
				(type default)
			)
			(layer "B.Fab")
		)
		(pad "1" smd rect
			(at 0 0 270)
			(size 0.508 0.508)
			(layers "B.Cu" "B.Mask" "B.Paste")
			(net "P3V3_STBY")
		)
		(pad "2" smd rect
			(at 0 0.889 270)
			(size 0.508 0.508)
			(layers "B.Cu" "B.Mask" "B.Paste")
			(net "GND")
		)
		(zone
			(layer "B.Cu")
			(hatch none 0.5)
			(connect_pads
				(clearance 0)
			)
			(min_thickness 0.25)
			(keepout
				(tracks allowed)
				(vias not_allowed)
				(pads allowed)
				(copperpour not_allowed)
				(footprints allowed)
			)
			(placement
				(enabled no)
				(sheetname "")
			)
			(fill
				(thermal_gap 0.5)
				(thermal_bridge_width 0.5)
				(island_removal_mode 0)
			)
			(polygon
				(pts
					(xy 392.295888 -115.569746) (xy 392.295888 -115.061746) (xy 392.676888 -115.061746) (xy 392.676888 -115.569746)
				)
			)
		)
		(zone
			(layer "B.Cu")
			(hatch none 0.5)
			(connect_pads
				(clearance 0)
			)
			(min_thickness 0.25)
			(keepout
				(tracks not_allowed)
				(vias allowed)
				(pads allowed)
				(copperpour not_allowed)
				(footprints allowed)
			)
			(placement
				(enabled no)
				(sheetname "")
			)
			(fill
				(thermal_gap 0.5)
				(thermal_bridge_width 0.5)
				(island_removal_mode 0)
			)
			(polygon
				(pts
					(xy 392.676888 -115.569746) (xy 392.676888 -115.061746) (xy 392.295888 -115.061746) (xy 392.295888 -115.569746)
				)
			)
		)
	)
)
